(kicad_pcb
	(version 20260206)
	(generator "pcbnew")
	(generator_version "10.0")
	(general
		(thickness 1.6)
		(legacy_teardrops no)
	)
	(paper "A4")
	(title_block
		(title "01162023_DA0F0TEBIF0_F0T_Expander_BD_F_brd_V02_OCP.brd")
		(comment 1 "Grand Teton / footprints 8033-8042 of 9728")
	)
	(layers
		(0 "F.Cu" signal "TOP")
		(4 "In1.Cu" signal "GND")
		(6 "In2.Cu" signal "VCC")
		(8 "In3.Cu" signal "VCC1")
		(10 "In4.Cu" signal "GND1")
		(12 "In5.Cu" signal "IN1")
		(14 "In6.Cu" signal "GND2")
		(16 "In7.Cu" signal "IN2")
		(18 "In8.Cu" signal "GND3")
		(20 "In9.Cu" signal "IN3")
		(22 "In10.Cu" signal "GND4")
		(24 "In11.Cu" signal "IN4")
		(26 "In12.Cu" signal "GND5")
		(28 "In13.Cu" signal "IN5")
		(30 "In14.Cu" signal "GND6")
		(32 "In15.Cu" signal "IN6")
		(34 "In16.Cu" signal "GND7")
		(2 "B.Cu" signal "BOTTOM")
		(9 "F.Adhes" user "F.Adhesive")
		(11 "B.Adhes" user "B.Adhesive")
		(13 "F.Paste" user "Package Geometry/Pastemask Top")
		(15 "B.Paste" user "Package Geometry/Pastemask Bottom")
		(5 "F.SilkS" user "Ref Des/Silkscreen Top")
		(7 "B.SilkS" user "Ref Des/Silkscreen Bottom")
		(1 "F.Mask" user "Board Geometry/Soldermask Top")
		(3 "B.Mask" user "Board Geometry/Soldermask Bottom")
		(17 "Dwgs.User" user "User.Drawings")
		(19 "Cmts.User" user "User.Comments")
		(21 "Eco1.User" user "User.Eco1")
		(23 "Eco2.User" user "User.Eco2")
		(25 "Edge.Cuts" user "Board Geometry/Outline")
		(27 "Margin" user)
		(31 "F.CrtYd" user "Package Geometry/Place Bound Top")
		(29 "B.CrtYd" user "Package Geometry/Place Bound Bottom")
		(35 "F.Fab" user "Ref Des/Assembly Top")
		(33 "B.Fab" user "Ref Des/Assembly Bottom")
	)
	(footprint ""
		(layer "B.Cu")
		(at 109.85119 -335.481676 -90)
		(property "Reference" "R1223"
			(at 0 0 90)
			(layer "B.SilkS")
			(hide yes)
			(effects
				(font
					(size 1.27 1.27)
				)
				(justify mirror)
			)
		)
		(property "Value" ""
			(at 0 0 90)
			(layer "B.Fab")
			(effects
				(font
					(size 1.27 1.27)
				)
				(justify mirror)
			)
		)
		(duplicate_pad_numbers_are_jumpers no)
		(fp_line
			(start -0.7874 0.4064)
			(end 0.7874 0.4064)
			(stroke
				(width 0.1524)
				(type default)
			)
			(layer "B.SilkS")
		)
		(fp_line
			(start 0.7874 0.4064)
			(end 0.7874 -0.4064)
			(stroke
				(width 0.1524)
				(type default)
			)
			(layer "B.SilkS")
		)
		(fp_line
			(start -0.7874 -0.4064)
			(end -0.7874 0.4064)
			(stroke
				(width 0.1524)
				(type default)
			)
			(layer "B.SilkS")
		)
		(fp_line
			(start 0.7874 -0.4064)
			(end -0.7874 -0.4064)
			(stroke
				(width 0.1524)
				(type default)
			)
			(layer "B.SilkS")
		)
		(fp_line
			(start -0.67945 0.3048)
			(end -0.120396 0.3048)
			(stroke
				(width 0.1)
				(type default)
			)
			(layer "B.Fab")
		)
		(fp_line
			(start -0.120396 0.3048)
			(end -0.120396 0.2794)
			(stroke
				(width 0.1)
				(type default)
			)
			(layer "B.Fab")
		)
		(fp_line
			(start 0.12065 0.3048)
			(end 0.67945 0.3048)
			(stroke
				(width 0.1)
				(type default)
			)
			(layer "B.Fab")
		)
		(fp_line
			(start 0.67945 0.3048)
			(end 0.67945 -0.305054)
			(stroke
				(width 0.1)
				(type default)
			)
			(layer "B.Fab")
		)
		(fp_line
			(start -0.120396 0.2794)
			(end 0.12065 0.2794)
			(stroke
				(width 0.1)
				(type default)
			)
			(layer "B.Fab")
		)
		(fp_line
			(start 0.12065 0.2794)
			(end 0.12065 0.3048)
			(stroke
				(width 0.1)
				(type default)
			)
			(layer "B.Fab")
		)
		(fp_line
			(start -0.12065 -0.2794)
			(end -0.12065 -0.3048)
			(stroke
				(width 0.1)
				(type default)
			)
			(layer "B.Fab")
		)
		(fp_line
			(start 0.12065 -0.2794)
			(end -0.12065 -0.2794)
			(stroke
				(width 0.1)
				(type default)
			)
			(layer "B.Fab")
		)
		(fp_line
			(start -0.67945 -0.3048)
			(end -0.67945 0.3048)
			(stroke
				(width 0.1)
				(type default)
			)
			(layer "B.Fab")
		)
		(fp_line
			(start -0.12065 -0.3048)
			(end -0.67945 -0.3048)
			(stroke
				(width 0.1)
				(type default)
			)
			(layer "B.Fab")
		)
		(fp_line
			(start 0.12065 -0.305054)
			(end 0.12065 -0.2794)
			(stroke
				(width 0.1)
				(type default)
			)
			(layer "B.Fab")
		)
		(fp_line
			(start 0.67945 -0.305054)
			(end 0.12065 -0.305054)
			(stroke
				(width 0.1)
				(type default)
			)
			(layer "B.Fab")
		)
		(pad "1" smd circle
			(at 0.40005 0 90)
			(size 0 0)
			(layers "B.Cu" "B.Mask" "B.Paste")
			(net "PU_9ZXL0451E_HBW")
		)
		(pad "2" smd circle
			(at -0.40005 0 90)
			(size 0 0)
			(layers "B.Cu" "B.Mask" "B.Paste")
			(net "GND")
		)
	)
	(footprint ""
		(layer "B.Cu")
		(at 55.374794 -286.399732 90)
		(property "Reference" "C2955"
			(at 0 0 90)
			(layer "B.SilkS")
			(hide yes)
			(effects
				(font
					(size 1.27 1.27)
				)
				(justify mirror)
			)
		)
		(property "Value" ""
			(at 0 0 90)
			(layer "B.Fab")
			(effects
				(font
					(size 1.27 1.27)
				)
				(justify mirror)
			)
		)
		(duplicate_pad_numbers_are_jumpers no)
		(fp_line
			(start 0.299974 -0.150114)
			(end -0.299974 -0.150114)
			(stroke
				(width 0.1)
				(type default)
			)
			(layer "B.Fab")
		)
		(fp_line
			(start -0.299974 -0.150114)
			(end -0.299974 0.150114)
			(stroke
				(width 0.1)
				(type default)
			)
			(layer "B.Fab")
		)
		(fp_line
			(start 0.299974 0.150114)
			(end 0.299974 -0.150114)
			(stroke
				(width 0.1)
				(type default)
			)
			(layer "B.Fab")
		)
		(fp_line
			(start -0.299974 0.150114)
			(end 0.299974 0.150114)
			(stroke
				(width 0.1)
				(type default)
			)
			(layer "B.Fab")
		)
		(pad "1" smd rect
			(at 0.2667 0 270)
			(size 0.3048 0.381)
			(layers "B.Cu" "B.Mask" "B.Paste")
			(net "P1V25_SERDES_VDDPLL_PEX0")
		)
		(pad "2" smd rect
			(at -0.2667 0 270)
			(size 0.3048 0.381)
			(layers "B.Cu" "B.Mask" "B.Paste")
			(net "GND")
		)
	)
	(footprint ""
		(layer "B.Cu")
		(at 170.049952 -292.099746 90)
		(property "Reference" "C1490"
			(at 0 0 90)
			(layer "B.SilkS")
			(hide yes)
			(effects
				(font
					(size 1.27 1.27)
				)
				(justify mirror)
			)
		)
		(property "Value" ""
			(at 0 0 90)
			(layer "B.Fab")
			(effects
				(font
					(size 1.27 1.27)
				)
				(justify mirror)
			)
		)
		(duplicate_pad_numbers_are_jumpers no)
		(fp_line
			(start 0.299974 -0.150114)
			(end -0.299974 -0.150114)
			(stroke
				(width 0.1)
				(type default)
			)
			(layer "B.Fab")
		)
		(fp_line
			(start -0.299974 -0.150114)
			(end -0.299974 0.150114)
			(stroke
				(width 0.1)
				(type default)
			)
			(layer "B.Fab")
		)
		(fp_line
			(start 0.299974 0.150114)
			(end 0.299974 -0.150114)
			(stroke
				(width 0.1)
				(type default)
			)
			(layer "B.Fab")
		)
		(fp_line
			(start -0.299974 0.150114)
			(end 0.299974 0.150114)
			(stroke
				(width 0.1)
				(type default)
			)
			(layer "B.Fab")
		)
		(pad "1" smd rect
			(at 0.2667 0 270)
			(size 0.3048 0.381)
			(layers "B.Cu" "B.Mask" "B.Paste")
			(net "P0V8_SERDES_VDDA_PEX1")
		)
		(pad "2" smd rect
			(at -0.2667 0 270)
			(size 0.3048 0.381)
			(layers "B.Cu" "B.Mask" "B.Paste")
			(net "GND")
		)
	)
	(footprint ""
		(layer "B.Cu")
		(at 399.400014 -303.499774 -90)
		(property "Reference" "C3438"
			(at 0 0 90)
			(layer "B.SilkS")
			(hide yes)
			(effects
				(font
					(size 1.27 1.27)
				)
				(justify mirror)
			)
		)
		(property "Value" ""
			(at 0 0 90)
			(layer "B.Fab")
			(effects
				(font
					(size 1.27 1.27)
				)
				(justify mirror)
			)
		)
		(duplicate_pad_numbers_are_jumpers no)
		(fp_line
			(start -0.299974 0.150114)
			(end 0.299974 0.150114)
			(stroke
				(width 0.1)
				(type default)
			)
			(layer "B.Fab")
		)
		(fp_line
			(start 0.299974 0.150114)
			(end 0.299974 -0.150114)
			(stroke
				(width 0.1)
				(type default)
			)
			(layer "B.Fab")
		)
		(fp_line
			(start -0.299974 -0.150114)
			(end -0.299974 0.150114)
			(stroke
				(width 0.1)
				(type default)
			)
			(layer "B.Fab")
		)
		(fp_line
			(start 0.299974 -0.150114)
			(end -0.299974 -0.150114)
			(stroke
				(width 0.1)
				(type default)
			)
			(layer "B.Fab")
		)
		(pad "1" smd rect
			(at 0.2667 0 90)
			(size 0.3048 0.381)
			(layers "B.Cu" "B.Mask" "B.Paste")
			(net "P1V25_PEX3")
		)
		(pad "2" smd rect
			(at -0.2667 0 90)
			(size 0.3048 0.381)
			(layers "B.Cu" "B.Mask" "B.Paste")
			(net "GND")
		)
	)
	(footprint ""
		(layer "B.Cu")
		(at 358.440736 -321.84594 -90)
		(property "Reference" "R6537"
			(at 0 0 90)
			(layer "B.SilkS")
			(hide yes)
			(effects
				(font
					(size 1.27 1.27)
				)
				(justify mirror)
			)
		)
		(property "Value" ""
			(at 0 0 90)
			(layer "B.Fab")
			(effects
				(font
					(size 1.27 1.27)
				)
				(justify mirror)
			)
		)
		(duplicate_pad_numbers_are_jumpers no)
		(fp_line
			(start -0.7874 0.4064)
			(end 0.7874 0.4064)
			(stroke
				(width 0.1524)
				(type default)
			)
			(layer "B.SilkS")
		)
		(fp_line
			(start 0.7874 0.4064)
			(end 0.7874 -0.4064)
			(stroke
				(width 0.1524)
				(type default)
			)
			(layer "B.SilkS")
		)
		(fp_line
			(start -0.7874 -0.4064)
			(end -0.7874 0.4064)
			(stroke
				(width 0.1524)
				(type default)
			)
			(layer "B.SilkS")
		)
		(fp_line
			(start 0.7874 -0.4064)
			(end -0.7874 -0.4064)
			(stroke
				(width 0.1524)
				(type default)
			)
			(layer "B.SilkS")
		)
		(fp_line
			(start -0.67945 0.3048)
			(end -0.120396 0.3048)
			(stroke
				(width 0.1)
				(type default)
			)
			(layer "B.Fab")
		)
		(fp_line
			(start -0.120396 0.3048)
			(end -0.120396 0.2794)
			(stroke
				(width 0.1)
				(type default)
			)
			(layer "B.Fab")
		)
		(fp_line
			(start 0.12065 0.3048)
			(end 0.67945 0.3048)
			(stroke
				(width 0.1)
				(type default)
			)
			(layer "B.Fab")
		)
		(fp_line
			(start 0.67945 0.3048)
			(end 0.67945 -0.305054)
			(stroke
				(width 0.1)
				(type default)
			)
			(layer "B.Fab")
		)
		(fp_line
			(start -0.120396 0.2794)
			(end 0.12065 0.2794)
			(stroke
				(width 0.1)
				(type default)
			)
			(layer "B.Fab")
		)
		(fp_line
			(start 0.12065 0.2794)
			(end 0.12065 0.3048)
			(stroke
				(width 0.1)
				(type default)
			)
			(layer "B.Fab")
		)
		(fp_line
			(start -0.12065 -0.2794)
			(end -0.12065 -0.3048)
			(stroke
				(width 0.1)
				(type default)
			)
			(layer "B.Fab")
		)
		(fp_line
			(start 0.12065 -0.2794)
			(end -0.12065 -0.2794)
			(stroke
				(width 0.1)
				(type default)
			)
			(layer "B.Fab")
		)
		(fp_line
			(start -0.67945 -0.3048)
			(end -0.67945 0.3048)
			(stroke
				(width 0.1)
				(type default)
			)
			(layer "B.Fab")
		)
		(fp_line
			(start -0.12065 -0.3048)
			(end -0.67945 -0.3048)
			(stroke
				(width 0.1)
				(type default)
			)
			(layer "B.Fab")
		)
		(fp_line
			(start 0.12065 -0.305054)
			(end 0.12065 -0.2794)
			(stroke
				(width 0.1)
				(type default)
			)
			(layer "B.Fab")
		)
		(fp_line
			(start 0.67945 -0.305054)
			(end 0.12065 -0.305054)
			(stroke
				(width 0.1)
				(type default)
			)
			(layer "B.Fab")
		)
		(pad "1" smd circle
			(at 0.40005 0 90)
			(size 0 0)
			(layers "B.Cu" "B.Mask" "B.Paste")
			(net "P0V8_SERDES_VDDA_PEX3")
		)
		(pad "2" smd circle
			(at -0.40005 0 90)
			(size 0 0)
			(layers "B.Cu" "B.Mask" "B.Paste")
			(net "P0V8_SERDES_VDDA_PEX3_C2")
		)
	)
	(footprint ""
		(layer "B.Cu")
		(at 71.049896 -297.32478 180)
		(property "Reference" "C2911"
			(at 0 0 0)
			(layer "B.SilkS")
			(hide yes)
			(effects
				(font
					(size 1.27 1.27)
				)
				(justify mirror)
			)
		)
		(property "Value" ""
			(at 0 0 0)
			(layer "B.Fab")
			(effects
				(font
					(size 1.27 1.27)
				)
				(justify mirror)
			)
		)
		(duplicate_pad_numbers_are_jumpers no)
		(fp_line
			(start 0.299974 0.150114)
			(end 0.299974 -0.150114)
			(stroke
				(width 0.1)
				(type default)
			)
			(layer "B.Fab")
		)
		(fp_line
			(start 0.299974 -0.150114)
			(end -0.299974 -0.150114)
			(stroke
				(width 0.1)
				(type default)
			)
			(layer "B.Fab")
		)
		(fp_line
			(start -0.299974 0.150114)
			(end 0.299974 0.150114)
			(stroke
				(width 0.1)
				(type default)
			)
			(layer "B.Fab")
		)
		(fp_line
			(start -0.299974 -0.150114)
			(end -0.299974 0.150114)
			(stroke
				(width 0.1)
				(type default)
			)
			(layer "B.Fab")
		)
		(pad "1" smd rect
			(at 0.2667 0)
			(size 0.3048 0.381)
			(layers "B.Cu" "B.Mask" "B.Paste")
			(net "P1V25_PEX0")
		)
		(pad "2" smd rect
			(at -0.2667 0)
			(size 0.3048 0.381)
			(layers "B.Cu" "B.Mask" "B.Paste")
			(net "GND")
		)
	)
	(footprint ""
		(layer "B.Cu")
		(at 175.749966 -288.299906 90)
		(property "Reference" "C3099"
			(at 0 0 90)
			(layer "B.SilkS")
			(hide yes)
			(effects
				(font
					(size 1.27 1.27)
				)
				(justify mirror)
			)
		)
		(property "Value" ""
			(at 0 0 90)
			(layer "B.Fab")
			(effects
				(font
					(size 1.27 1.27)
				)
				(justify mirror)
			)
		)
		(duplicate_pad_numbers_are_jumpers no)
		(fp_line
			(start 0.299974 -0.150114)
			(end -0.299974 -0.150114)
			(stroke
				(width 0.1)
				(type default)
			)
			(layer "B.Fab")
		)
		(fp_line
			(start -0.299974 -0.150114)
			(end -0.299974 0.150114)
			(stroke
				(width 0.1)
				(type default)
			)
			(layer "B.Fab")
		)
		(fp_line
			(start 0.299974 0.150114)
			(end 0.299974 -0.150114)
			(stroke
				(width 0.1)
				(type default)
			)
			(layer "B.Fab")
		)
		(fp_line
			(start -0.299974 0.150114)
			(end 0.299974 0.150114)
			(stroke
				(width 0.1)
				(type default)
			)
			(layer "B.Fab")
		)
		(pad "1" smd rect
			(at 0.2667 0 270)
			(size 0.3048 0.381)
			(layers "B.Cu" "B.Mask" "B.Paste")
			(net "P1V25_PEX1")
		)
		(pad "2" smd rect
			(at -0.2667 0 270)
			(size 0.3048 0.381)
			(layers "B.Cu" "B.Mask" "B.Paste")
			(net "GND")
		)
	)
	(footprint ""
		(layer "B.Cu")
		(at 176.491646 -296.37482 180)
		(property "Reference" "C1373"
			(at 0 0 0)
			(layer "B.SilkS")
			(hide yes)
			(effects
				(font
					(size 1.27 1.27)
				)
				(justify mirror)
			)
		)
		(property "Value" ""
			(at 0 0 0)
			(layer "B.Fab")
			(effects
				(font
					(size 1.27 1.27)
				)
				(justify mirror)
			)
		)
		(duplicate_pad_numbers_are_jumpers no)
		(fp_line
			(start 0.299974 0.150114)
			(end 0.299974 -0.150114)
			(stroke
				(width 0.1)
				(type default)
			)
			(layer "B.Fab")
		)
		(fp_line
			(start 0.299974 -0.150114)
			(end -0.299974 -0.150114)
			(stroke
				(width 0.1)
				(type default)
			)
			(layer "B.Fab")
		)
		(fp_line
			(start -0.299974 0.150114)
			(end 0.299974 0.150114)
			(stroke
				(width 0.1)
				(type default)
			)
			(layer "B.Fab")
		)
		(fp_line
			(start -0.299974 -0.150114)
			(end -0.299974 0.150114)
			(stroke
				(width 0.1)
				(type default)
			)
			(layer "B.Fab")
		)
		(pad "1" smd rect
			(at 0.2667 0)
			(size 0.3048 0.381)
			(layers "B.Cu" "B.Mask" "B.Paste")
			(net "P0V8_PEX1")
		)
		(pad "2" smd rect
			(at -0.2667 0)
			(size 0.3048 0.381)
			(layers "B.Cu" "B.Mask" "B.Paste")
			(net "GND")
		)
	)
	(footprint ""
		(layer "B.Cu")
		(at 171.474892 -286.399732 90)
		(property "Reference" "C3133"
			(at 0 0 90)
			(layer "B.SilkS")
			(hide yes)
			(effects
				(font
					(size 1.27 1.27)
				)
				(justify mirror)
			)
		)
		(property "Value" ""
			(at 0 0 90)
			(layer "B.Fab")
			(effects
				(font
					(size 1.27 1.27)
				)
				(justify mirror)
			)
		)
		(duplicate_pad_numbers_are_jumpers no)
		(fp_line
			(start 0.299974 -0.150114)
			(end -0.299974 -0.150114)
			(stroke
				(width 0.1)
				(type default)
			)
			(layer "B.Fab")
		)
		(fp_line
			(start -0.299974 -0.150114)
			(end -0.299974 0.150114)
			(stroke
				(width 0.1)
				(type default)
			)
			(layer "B.Fab")
		)
		(fp_line
			(start 0.299974 0.150114)
			(end 0.299974 -0.150114)
			(stroke
				(width 0.1)
				(type default)
			)
			(layer "B.Fab")
		)
		(fp_line
			(start -0.299974 0.150114)
			(end 0.299974 0.150114)
			(stroke
				(width 0.1)
				(type default)
			)
			(layer "B.Fab")
		)
		(pad "1" smd rect
			(at 0.2667 0 270)
			(size 0.3048 0.381)
			(layers "B.Cu" "B.Mask" "B.Paste")
			(net "P1V25_SERDES_VDDPLL_PEX1")
		)
		(pad "2" smd rect
			(at -0.2667 0 270)
			(size 0.3048 0.381)
			(layers "B.Cu" "B.Mask" "B.Paste")
			(net "GND")
		)
	)
	(footprint ""
		(layer "B.Cu")
		(at 62.974728 -293.99992 90)
		(property "Reference" "C1142"
			(at 0 0 90)
			(layer "B.SilkS")
			(hide yes)
			(effects
				(font
					(size 1.27 1.27)
				)
				(justify mirror)
			)
		)
		(property "Value" ""
			(at 0 0 90)
			(layer "B.Fab")
			(effects
				(font
					(size 1.27 1.27)
				)
				(justify mirror)
			)
		)
		(duplicate_pad_numbers_are_jumpers no)
		(fp_line
			(start 0.299974 -0.150114)
			(end -0.299974 -0.150114)
			(stroke
				(width 0.1)
				(type default)
			)
			(layer "B.Fab")
		)
		(fp_line
			(start -0.299974 -0.150114)
			(end -0.299974 0.150114)
			(stroke
				(width 0.1)
				(type default)
			)
			(layer "B.Fab")
		)
		(fp_line
			(start 0.299974 0.150114)
			(end 0.299974 -0.150114)
			(stroke
				(width 0.1)
				(type default)
			)
			(layer "B.Fab")
		)
		(fp_line
			(start -0.299974 0.150114)
			(end 0.299974 0.150114)
			(stroke
				(width 0.1)
				(type default)
			)
			(layer "B.Fab")
		)
		(pad "1" smd rect
			(at 0.2667 0 270)
			(size 0.3048 0.381)
			(layers "B.Cu" "B.Mask" "B.Paste")
			(net "P0V8_PEX0")
		)
		(pad "2" smd rect
			(at -0.2667 0 270)
			(size 0.3048 0.381)
			(layers "B.Cu" "B.Mask" "B.Paste")
			(net "GND")
		)
	)
)
